# T6G (Grand Teton) — schematic netlist excerpt (pin names and nets, part order shuffled) for the footprints in the layout excerpt that follows; sources: Cadence DE-HDL packaged netlist, KiCad conversion of 04192023_DAF0TMB3IC0_F0TG_MB_C_brd_V02_OCP.brd

R371  Q_RES  33 5% CHIP  pkg 0402LF  page 81 : A = FPGA_DEBUG_LED_CTRL ; B = FM_FPGA_DEBUG_LED_CTRL
R795  Q_RES  1K 1% EMPTY  pkg 0201LF  page 331 : A = P1V8_CPU1_RT_1D ; B = RT_CPU1_P1_ADDR1
R3063  Q_RES  0 5% CHIP  pkg 0402LF  page 130 : A = FM_PDB_BUF_EN_R1 ; B = FM_UART_EN

(kicad_pcb
	(version 20260206)
	(generator "pcbnew")
	(generator_version "10.0")
	(general
		(thickness 1.6)
		(legacy_teardrops no)
	)
	(paper "A4")
	(title_block
		(title "04192023_DAF0TMB3IC0_F0TG_MB_C_brd_V02_OCP.brd")
		(comment 1 "Grand Teton / footprints 3323-3325 of 8354")
	)
	(layers
		(0 "F.Cu" signal "TOP")
		(4 "In1.Cu" signal "GND")
		(6 "In2.Cu" signal "IN1")
		(8 "In3.Cu" signal "GND1")
		(10 "In4.Cu" signal "IN2")
		(12 "In5.Cu" signal "GND2")
		(14 "In6.Cu" signal "IN3")
		(16 "In7.Cu" signal "GND3")
		(18 "In8.Cu" signal "VCC")
		(20 "In9.Cu" signal "VCC1")
		(22 "In10.Cu" signal "GND4")
		(24 "In11.Cu" signal "IN4")
		(26 "In12.Cu" signal "GND5")
		(28 "In13.Cu" signal "IN5")
		(30 "In14.Cu" signal "GND6")
		(32 "In15.Cu" signal "IN6")
		(34 "In16.Cu" signal "GND7")
		(2 "B.Cu" signal "BOTTOM")
		(9 "F.Adhes" user "F.Adhesive")
		(11 "B.Adhes" user "B.Adhesive")
		(13 "F.Paste" user "Package Geometry/Pastemask Top")
		(15 "B.Paste" user "Package Geometry/Pastemask Bottom")
		(5 "F.SilkS" user "Ref Des/Silkscreen Top")
		(7 "B.SilkS" user "Ref Des/Silkscreen Bottom")
		(1 "F.Mask" user "Board Geometry/Soldermask Top")
		(3 "B.Mask" user "Board Geometry/Soldermask Bottom")
		(17 "Dwgs.User" user "User.Drawings")
		(19 "Cmts.User" user "User.Comments")
		(21 "Eco1.User" user "User.Eco1")
		(23 "Eco2.User" user "User.Eco2")
		(25 "Edge.Cuts" user "Board Geometry/Outline")
		(27 "Margin" user)
		(31 "F.CrtYd" user "Package Geometry/Place Bound Top")
		(29 "B.CrtYd" user "Package Geometry/Place Bound Bottom")
		(35 "F.Fab" user "Ref Des/Assembly Top")
		(33 "B.Fab" user "Ref Des/Assembly Bottom")
	)
	(footprint ""
		(layer "F.Cu")
		(at 358.297988 -409.388818 90)
		(property "Reference" "R3063"
			(at 0 0 90)
			(layer "F.SilkS")
			(hide yes)
			(effects
				(font
					(size 1.27 1.27)
				)
			)
		)
		(property "Value" ""
			(at 0 0 90)
			(layer "F.Fab")
			(effects
				(font
					(size 1.27 1.27)
				)
			)
		)
		(duplicate_pad_numbers_are_jumpers no)
		(fp_line
			(start 0.7874 -0.4064)
			(end 0.7874 0.4064)
			(stroke
				(width 0.1524)
				(type default)
			)
			(layer "F.SilkS")
		)
		(fp_line
			(start -0.7874 -0.4064)
			(end 0.7874 -0.4064)
			(stroke
				(width 0.1524)
				(type default)
			)
			(layer "F.SilkS")
		)
		(fp_line
			(start 0.7874 0.4064)
			(end -0.7874 0.4064)
			(stroke
				(width 0.1524)
				(type default)
			)
			(layer "F.SilkS")
		)
		(fp_line
			(start -0.7874 0.4064)
			(end -0.7874 -0.4064)
			(stroke
				(width 0.1524)
				(type default)
			)
			(layer "F.SilkS")
		)
		(fp_line
			(start -0.12065 -0.305054)
			(end -0.12065 -0.2794)
			(stroke
				(width 0.1)
				(type default)
			)
			(layer "F.Fab")
		)
		(fp_line
			(start -0.67945 -0.305054)
			(end -0.12065 -0.305054)
			(stroke
				(width 0.1)
				(type default)
			)
			(layer "F.Fab")
		)
		(fp_line
			(start 0.67945 -0.3048)
			(end 0.67945 0.3048)
			(stroke
				(width 0.1)
				(type default)
			)
			(layer "F.Fab")
		)
		(fp_line
			(start 0.12065 -0.3048)
			(end 0.67945 -0.3048)
			(stroke
				(width 0.1)
				(type default)
			)
			(layer "F.Fab")
		)
		(fp_line
			(start 0.12065 -0.2794)
			(end 0.12065 -0.3048)
			(stroke
				(width 0.1)
				(type default)
			)
			(layer "F.Fab")
		)
		(fp_line
			(start -0.12065 -0.2794)
			(end 0.12065 -0.2794)
			(stroke
				(width 0.1)
				(type default)
			)
			(layer "F.Fab")
		)
		(fp_line
			(start 0.120396 0.2794)
			(end -0.12065 0.2794)
			(stroke
				(width 0.1)
				(type default)
			)
			(layer "F.Fab")
		)
		(fp_line
			(start -0.12065 0.2794)
			(end -0.12065 0.3048)
			(stroke
				(width 0.1)
				(type default)
			)
			(layer "F.Fab")
		)
		(fp_line
			(start 0.67945 0.3048)
			(end 0.120396 0.3048)
			(stroke
				(width 0.1)
				(type default)
			)
			(layer "F.Fab")
		)
		(fp_line
			(start 0.120396 0.3048)
			(end 0.120396 0.2794)
			(stroke
				(width 0.1)
				(type default)
			)
			(layer "F.Fab")
		)
		(fp_line
			(start -0.12065 0.3048)
			(end -0.67945 0.3048)
			(stroke
				(width 0.1)
				(type default)
			)
			(layer "F.Fab")
		)
		(fp_line
			(start -0.67945 0.3048)
			(end -0.67945 -0.305054)
			(stroke
				(width 0.1)
				(type default)
			)
			(layer "F.Fab")
		)
		(pad "1" smd circle
			(at -0.40005 0 90)
			(size 0 0)
			(layers "F.Cu" "F.Mask" "F.Paste")
			(net "FM_PDB_BUF_EN_R1")
		)
		(pad "2" smd circle
			(at 0.40005 0 90)
			(size 0 0)
			(layers "F.Cu" "F.Mask" "F.Paste")
			(net "FM_UART_EN")
		)
	)
	(footprint ""
		(layer "F.Cu")
		(at 179.959 -137.632948 -90)
		(property "Reference" "R371"
			(at 0 0 270)
			(layer "F.SilkS")
			(hide yes)
			(effects
				(font
					(size 1.27 1.27)
				)
			)
		)
		(property "Value" ""
			(at 0 0 270)
			(layer "F.Fab")
			(effects
				(font
					(size 1.27 1.27)
				)
			)
		)
		(duplicate_pad_numbers_are_jumpers no)
		(fp_line
			(start -0.7874 0.4064)
			(end -0.7874 -0.4064)
			(stroke
				(width 0.1524)
				(type default)
			)
			(layer "F.SilkS")
		)
		(fp_line
			(start 0.7874 0.4064)
			(end -0.7874 0.4064)
			(stroke
				(width 0.1524)
				(type default)
			)
			(layer "F.SilkS")
		)
		(fp_line
			(start -0.7874 -0.4064)
			(end 0.7874 -0.4064)
			(stroke
				(width 0.1524)
				(type default)
			)
			(layer "F.SilkS")
		)
		(fp_line
			(start 0.7874 -0.4064)
			(end 0.7874 0.4064)
			(stroke
				(width 0.1524)
				(type default)
			)
			(layer "F.SilkS")
		)
		(fp_line
			(start -0.67945 0.3048)
			(end -0.67945 -0.305054)
			(stroke
				(width 0.1)
				(type default)
			)
			(layer "F.Fab")
		)
		(fp_line
			(start -0.12065 0.3048)
			(end -0.67945 0.3048)
			(stroke
				(width 0.1)
				(type default)
			)
			(layer "F.Fab")
		)
		(fp_line
			(start 0.120396 0.3048)
			(end 0.120396 0.2794)
			(stroke
				(width 0.1)
				(type default)
			)
			(layer "F.Fab")
		)
		(fp_line
			(start 0.67945 0.3048)
			(end 0.120396 0.3048)
			(stroke
				(width 0.1)
				(type default)
			)
			(layer "F.Fab")
		)
		(fp_line
			(start -0.12065 0.2794)
			(end -0.12065 0.3048)
			(stroke
				(width 0.1)
				(type default)
			)
			(layer "F.Fab")
		)
		(fp_line
			(start 0.120396 0.2794)
			(end -0.12065 0.2794)
			(stroke
				(width 0.1)
				(type default)
			)
			(layer "F.Fab")
		)
		(fp_line
			(start -0.12065 -0.2794)
			(end 0.12065 -0.2794)
			(stroke
				(width 0.1)
				(type default)
			)
			(layer "F.Fab")
		)
		(fp_line
			(start 0.12065 -0.2794)
			(end 0.12065 -0.3048)
			(stroke
				(width 0.1)
				(type default)
			)
			(layer "F.Fab")
		)
		(fp_line
			(start 0.12065 -0.3048)
			(end 0.67945 -0.3048)
			(stroke
				(width 0.1)
				(type default)
			)
			(layer "F.Fab")
		)
		(fp_line
			(start 0.67945 -0.3048)
			(end 0.67945 0.3048)
			(stroke
				(width 0.1)
				(type default)
			)
			(layer "F.Fab")
		)
		(fp_line
			(start -0.67945 -0.305054)
			(end -0.12065 -0.305054)
			(stroke
				(width 0.1)
				(type default)
			)
			(layer "F.Fab")
		)
		(fp_line
			(start -0.12065 -0.305054)
			(end -0.12065 -0.2794)
			(stroke
				(width 0.1)
				(type default)
			)
			(layer "F.Fab")
		)
		(pad "1" smd circle
			(at -0.40005 0 270)
			(size 0 0)
			(layers "F.Cu" "F.Mask" "F.Paste")
			(net "FPGA_DEBUG_LED_CTRL")
		)
		(pad "2" smd circle
			(at 0.40005 0 270)
			(size 0 0)
			(layers "F.Cu" "F.Mask" "F.Paste")
			(net "FM_FPGA_DEBUG_LED_CTRL")
		)
	)
	(footprint ""
		(layer "F.Cu")
		(at 103.495348 -382.6764 180)
		(property "Reference" "R795"
			(at 0 0 180)
			(layer "F.SilkS")
			(hide yes)
			(effects
				(font
					(size 1.27 1.27)
				)
			)
		)
		(property "Value" ""
			(at 0 0 180)
			(layer "F.Fab")
			(effects
				(font
					(size 1.27 1.27)
				)
			)
		)
		(duplicate_pad_numbers_are_jumpers no)
		(fp_line
			(start 0.32512 0.175006)
			(end -0.32512 0.175006)
			(stroke
				(width 0.1)
				(type default)
			)
			(layer "F.Fab")
		)
		(fp_line
			(start 0.32512 -0.175006)
			(end 0.32512 0.175006)
			(stroke
				(width 0.1)
				(type default)
			)
			(layer "F.Fab")
		)
		(fp_line
			(start -0.32512 0.175006)
			(end -0.32512 -0.175006)
			(stroke
				(width 0.1)
				(type default)
			)
			(layer "F.Fab")
		)
		(fp_line
			(start -0.32512 -0.175006)
			(end 0.32512 -0.175006)
			(stroke
				(width 0.1)
				(type default)
			)
			(layer "F.Fab")
		)
		(pad "1" smd rect
			(at -0.2667 0 180)
			(size 0.3048 0.381)
			(layers "F.Cu" "F.Mask" "F.Paste")
			(net "P1V8_CPU1_RT_1D")
		)
		(pad "2" smd rect
			(at 0.2667 0)
			(size 0.3048 0.381)
			(layers "F.Cu" "F.Mask" "F.Paste")
			(net "RT_CPU1_P1_ADDR1")
		)
	)
)
